FILE_TYPE = CONNECTIVITY;
{Allegro Design Entry HDL 17.2-2016 S081 (4005846) 1/11/2022}
"PAGE_NUMBER" = 205;
0"NC";
END.
